# BASEBOARD_FAB2 (Tioga Pass) — schematic netlist excerpt (pin names and nets, part order shuffled) for the footprints in the layout excerpt that follows; sources: Cadence DE-HDL packaged netlist, KiCad conversion of Wiwynn_Tioga_Pass_MB.brd

C845  CAP  0.22UF 16V 10% X7R  pkg 0402  page 244 : A = P3E_CPU0_PE1_PCH_TXP<9> ; B = P3E_CPU0_PE1_PCH_CON_TXP<9>
C7A5  CAP_A  0.1UF 16V 10% X7R  pkg 0402V  page 219 : A = VR_FET_SW_P12V_STBY_PVDDQ_DEF ; B = GND
C8F6  CAP_A  0.01UF 25V 10% X7R  pkg 0402V  page 185 : A = SATA6G_S0_TX_DP ; B = P3E_PCH_M2_SATA6G_TX_R_DP

(kicad_pcb
	(version 20260206)
	(generator "pcbnew")
	(generator_version "10.0")
	(general
		(thickness 1.6)
		(legacy_teardrops no)
	)
	(paper "A4")
	(title_block
		(title "Wiwynn_Tioga_Pass_MB.brd")
		(comment 1 "Tioga Pass / footprints 1521-1523 of 4770")
	)
	(layers
		(0 "F.Cu" signal "TOP")
		(4 "In1.Cu" signal "L2GND")
		(6 "In2.Cu" signal "L3")
		(8 "In3.Cu" signal "L4GND")
		(10 "In4.Cu" signal "L5")
		(12 "In5.Cu" signal "L6GND")
		(14 "In6.Cu" signal "L7VCC")
		(16 "In7.Cu" signal "L8VCC")
		(18 "In8.Cu" signal "L9GND")
		(20 "In9.Cu" signal "L10")
		(22 "In10.Cu" signal "L11GND")
		(24 "In11.Cu" signal "L12")
		(26 "In12.Cu" signal "L13GND")
		(2 "B.Cu" signal "BOTTOM")
		(9 "F.Adhes" user "F.Adhesive")
		(11 "B.Adhes" user "B.Adhesive")
		(13 "F.Paste" user "Package Geometry/Pastemask Top")
		(15 "B.Paste" user "Package Geometry/Pastemask Bottom")
		(5 "F.SilkS" user "Ref Des/Silkscreen Top")
		(7 "B.SilkS" user "Ref Des/Silkscreen Bottom")
		(1 "F.Mask" user "Board Geometry/Soldermask Top")
		(3 "B.Mask" user "Board Geometry/Soldermask Bottom")
		(17 "Dwgs.User" user "User.Drawings")
		(19 "Cmts.User" user "User.Comments")
		(21 "Eco1.User" user "User.Eco1")
		(23 "Eco2.User" user "User.Eco2")
		(25 "Edge.Cuts" user "Board Geometry/Outline")
		(27 "Margin" user)
		(31 "F.CrtYd" user "Package Geometry/Place Bound Top")
		(29 "B.CrtYd" user "Package Geometry/Place Bound Bottom")
		(35 "F.Fab" user "Ref Des/Assembly Top")
		(33 "B.Fab" user "Ref Des/Assembly Bottom")
	)
	(footprint ""
		(layer "F.Cu")
		(at 378.254768 -33.7185 90)
		(property "Reference" "C8F6"
			(at 0 0 90)
			(layer "F.SilkS")
			(hide yes)
			(effects
				(font
					(size 1.27 1.27)
				)
			)
		)
		(property "Value" ""
			(at 0 0 90)
			(layer "F.Fab")
			(effects
				(font
					(size 1.27 1.27)
				)
			)
		)
		(duplicate_pad_numbers_are_jumpers no)
		(fp_poly
			(pts
				(xy 0.3048 -0.1016) (xy 0.3048 0.9906) (xy -0.3048 0.9906) (xy -0.3048 -0.1016)
			)
			(stroke
				(width 0)
				(type default)
			)
			(fill no)
			(layer "F.CrtYd")
		)
		(fp_line
			(start 0.3048 -0.1016)
			(end -0.3048 -0.1016)
			(stroke
				(width 0.1)
				(type default)
			)
			(layer "F.Fab")
		)
		(fp_line
			(start -0.3048 -0.1016)
			(end -0.3048 0.9906)
			(stroke
				(width 0.1)
				(type default)
			)
			(layer "F.Fab")
		)
		(fp_line
			(start 0.3048 0.9906)
			(end 0.3048 -0.1016)
			(stroke
				(width 0.1)
				(type default)
			)
			(layer "F.Fab")
		)
		(fp_line
			(start -0.3048 0.9906)
			(end 0.3048 0.9906)
			(stroke
				(width 0.1)
				(type default)
			)
			(layer "F.Fab")
		)
		(pad "1" smd rect
			(at 0 0 90)
			(size 0.508 0.508)
			(layers "F.Cu" "F.Mask" "F.Paste")
			(net "SATA6G_S0_TX_DP")
		)
		(pad "2" smd rect
			(at 0 0.889 90)
			(size 0.508 0.508)
			(layers "F.Cu" "F.Mask" "F.Paste")
			(net "P3E_PCH_M2_SATA6G_TX_R_DP")
		)
		(zone
			(layer "F.Cu")
			(hatch none 0.5)
			(connect_pads
				(clearance 0)
			)
			(min_thickness 0.25)
			(keepout
				(tracks allowed)
				(vias not_allowed)
				(pads allowed)
				(copperpour not_allowed)
				(footprints allowed)
			)
			(placement
				(enabled no)
				(sheetname "")
			)
			(fill
				(thermal_gap 0.5)
				(thermal_bridge_width 0.5)
				(island_removal_mode 0)
			)
			(polygon
				(pts
					(xy 378.508768 -33.4645) (xy 378.508768 -33.9725) (xy 378.889768 -33.9725) (xy 378.889768 -33.4645)
				)
			)
		)
		(zone
			(layer "F.Cu")
			(hatch none 0.5)
			(connect_pads
				(clearance 0)
			)
			(min_thickness 0.25)
			(keepout
				(tracks not_allowed)
				(vias allowed)
				(pads allowed)
				(copperpour not_allowed)
				(footprints allowed)
			)
			(placement
				(enabled no)
				(sheetname "")
			)
			(fill
				(thermal_gap 0.5)
				(thermal_bridge_width 0.5)
				(island_removal_mode 0)
			)
			(polygon
				(pts
					(xy 378.889768 -33.4645) (xy 378.889768 -33.9725) (xy 378.508768 -33.9725) (xy 378.508768 -33.4645)
				)
			)
		)
	)
	(footprint ""
		(layer "F.Cu")
		(at 339.222588 -117.941598 -90)
		(property "Reference" "C845"
			(at -0.8382 -0.67818 270)
			(unlocked yes)
			(layer "F.SilkS")
			(effects
				(font
					(size 0.4064 0.254)
					(thickness 0.1524)
				)
				(justify left)
			)
		)
		(property "Value" ""
			(at 0 0 270)
			(layer "F.Fab")
			(effects
				(font
					(size 1.27 1.27)
				)
			)
		)
		(duplicate_pad_numbers_are_jumpers no)
		(fp_poly
			(pts
				(xy 0.3048 -0.1016) (xy 0.3048 0.9906) (xy -0.3048 0.9906) (xy -0.3048 -0.1016)
			)
			(stroke
				(width 0)
				(type default)
			)
			(fill no)
			(layer "F.CrtYd")
		)
		(fp_line
			(start -0.3048 0.9906)
			(end 0.3048 0.9906)
			(stroke
				(width 0.1)
				(type default)
			)
			(layer "F.Fab")
		)
		(fp_line
			(start 0.3048 0.9906)
			(end 0.3048 -0.1016)
			(stroke
				(width 0.1)
				(type default)
			)
			(layer "F.Fab")
		)
		(fp_line
			(start -0.3048 -0.1016)
			(end -0.3048 0.9906)
			(stroke
				(width 0.1)
				(type default)
			)
			(layer "F.Fab")
		)
		(fp_line
			(start 0.3048 -0.1016)
			(end -0.3048 -0.1016)
			(stroke
				(width 0.1)
				(type default)
			)
			(layer "F.Fab")
		)
		(pad "1" smd rect
			(at 0 0 270)
			(size 0.508 0.508)
			(layers "F.Cu" "F.Mask" "F.Paste")
			(net "P3E_CPU0_PE1_PCH_TXP<9>")
		)
		(pad "2" smd rect
			(at 0 0.889 270)
			(size 0.508 0.508)
			(layers "F.Cu" "F.Mask" "F.Paste")
			(net "P3E_CPU0_PE1_PCH_CON_TXP<9>")
		)
		(zone
			(layer "F.Cu")
			(hatch none 0.5)
			(connect_pads
				(clearance 0)
			)
			(min_thickness 0.25)
			(keepout
				(tracks not_allowed)
				(vias allowed)
				(pads allowed)
				(copperpour not_allowed)
				(footprints allowed)
			)
			(placement
				(enabled no)
				(sheetname "")
			)
			(fill
				(thermal_gap 0.5)
				(thermal_bridge_width 0.5)
				(island_removal_mode 0)
			)
			(polygon
				(pts
					(xy 338.587588 -118.195598) (xy 338.587588 -117.687598) (xy 338.968588 -117.687598) (xy 338.968588 -118.195598)
				)
			)
		)
		(zone
			(layer "F.Cu")
			(hatch none 0.5)
			(connect_pads
				(clearance 0)
			)
			(min_thickness 0.25)
			(keepout
				(tracks allowed)
				(vias not_allowed)
				(pads allowed)
				(copperpour not_allowed)
				(footprints allowed)
			)
			(placement
				(enabled no)
				(sheetname "")
			)
			(fill
				(thermal_gap 0.5)
				(thermal_bridge_width 0.5)
				(island_removal_mode 0)
			)
			(polygon
				(pts
					(xy 338.968588 -118.195598) (xy 338.968588 -117.687598) (xy 338.587588 -117.687598) (xy 338.587588 -118.195598)
				)
			)
		)
	)
	(footprint ""
		(layer "F.Cu")
		(at 348.053914 -149.939502 -90)
		(property "Reference" "C7A5"
			(at 0 0 270)
			(layer "F.SilkS")
			(hide yes)
			(effects
				(font
					(size 1.27 1.27)
				)
			)
		)
		(property "Value" ""
			(at 0 0 270)
			(layer "F.Fab")
			(effects
				(font
					(size 1.27 1.27)
				)
			)
		)
		(duplicate_pad_numbers_are_jumpers no)
		(fp_poly
			(pts
				(xy 0.3048 -0.1016) (xy 0.3048 0.9906) (xy -0.3048 0.9906) (xy -0.3048 -0.1016)
			)
			(stroke
				(width 0)
				(type default)
			)
			(fill no)
			(layer "F.CrtYd")
		)
		(fp_line
			(start -0.3048 0.9906)
			(end 0.3048 0.9906)
			(stroke
				(width 0.1)
				(type default)
			)
			(layer "F.Fab")
		)
		(fp_line
			(start 0.3048 0.9906)
			(end 0.3048 -0.1016)
			(stroke
				(width 0.1)
				(type default)
			)
			(layer "F.Fab")
		)
		(fp_line
			(start -0.3048 -0.1016)
			(end -0.3048 0.9906)
			(stroke
				(width 0.1)
				(type default)
			)
			(layer "F.Fab")
		)
		(fp_line
			(start 0.3048 -0.1016)
			(end -0.3048 -0.1016)
			(stroke
				(width 0.1)
				(type default)
			)
			(layer "F.Fab")
		)
		(pad "1" smd rect
			(at 0 0 270)
			(size 0.508 0.508)
			(layers "F.Cu" "F.Mask" "F.Paste")
			(net "VR_FET_SW_P12V_STBY_PVDDQ_DEF")
		)
		(pad "2" smd rect
			(at 0 0.889 270)
			(size 0.508 0.508)
			(layers "F.Cu" "F.Mask" "F.Paste")
			(net "GND")
		)
		(zone
			(layer "F.Cu")
			(hatch none 0.5)
			(connect_pads
				(clearance 0)
			)
			(min_thickness 0.25)
			(keepout
				(tracks not_allowed)
				(vias allowed)
				(pads allowed)
				(copperpour not_allowed)
				(footprints allowed)
			)
			(placement
				(enabled no)
				(sheetname "")
			)
			(fill
				(thermal_gap 0.5)
				(thermal_bridge_width 0.5)
				(island_removal_mode 0)
			)
			(polygon
				(pts
					(xy 347.418914 -150.193502) (xy 347.418914 -149.685502) (xy 347.799914 -149.685502) (xy 347.799914 -150.193502)
				)
			)
		)
		(zone
			(layer "F.Cu")
			(hatch none 0.5)
			(connect_pads
				(clearance 0)
			)
			(min_thickness 0.25)
			(keepout
				(tracks allowed)
				(vias not_allowed)
				(pads allowed)
				(copperpour not_allowed)
				(footprints allowed)
			)
			(placement
				(enabled no)
				(sheetname "")
			)
			(fill
				(thermal_gap 0.5)
				(thermal_bridge_width 0.5)
				(island_removal_mode 0)
			)
			(polygon
				(pts
					(xy 347.799914 -150.193502) (xy 347.799914 -149.685502) (xy 347.418914 -149.685502) (xy 347.418914 -150.193502)
				)
			)
		)
	)
)
